(kicad_pcb
	(version 20260206)
	(generator "pcbnew")
	(generator_version "10.0")
	(general
		(thickness 1.6)
		(legacy_teardrops no)
	)
	(paper "A4")
	(title_block
		(title "Bryce Canyon_IOM_IOC_16318-2_OCP.brd")
		(comment 1 "Bryce Canyon / footprints 638-643 of 1605")
	)
	(layers
		(0 "F.Cu" signal "TOP")
		(4 "In1.Cu" signal "L2GND")
		(6 "In2.Cu" signal "L3")
		(8 "In3.Cu" signal "L4VCC")
		(10 "In4.Cu" signal "L5VCC")
		(12 "In5.Cu" signal "L6")
		(14 "In6.Cu" signal "L7GND")
		(2 "B.Cu" signal "BOTTOM")
		(9 "F.Adhes" user "F.Adhesive")
		(11 "B.Adhes" user "B.Adhesive")
		(13 "F.Paste" user "Package Geometry/Pastemask Top")
		(15 "B.Paste" user "Package Geometry/Pastemask Bottom")
		(5 "F.SilkS" user "Ref Des/Silkscreen Top")
		(7 "B.SilkS" user "Ref Des/Silkscreen Bottom")
		(1 "F.Mask" user "Board Geometry/Soldermask Top")
		(3 "B.Mask" user "Board Geometry/Soldermask Bottom")
		(17 "Dwgs.User" user "User.Drawings")
		(19 "Cmts.User" user "User.Comments")
		(21 "Eco1.User" user "User.Eco1")
		(23 "Eco2.User" user "User.Eco2")
		(25 "Edge.Cuts" user "Board Geometry/Outline")
		(27 "Margin" user)
		(31 "F.CrtYd" user "Package Geometry/Place Bound Top")
		(29 "B.CrtYd" user "Package Geometry/Place Bound Bottom")
		(35 "F.Fab" user "Ref Des/Assembly Top")
		(33 "B.Fab" user "Ref Des/Assembly Bottom")
	)
	(footprint ""
		(layer "F.Cu")
		(at 85.471 -170.6372 180)
		(property "Reference" "R723"
			(at 0 0 180)
			(layer "F.SilkS")
			(hide yes)
			(effects
				(font
					(size 1.27 1.27)
				)
			)
		)
		(property "Value" "4K7R2F-GP"
			(at 0.064008 -3.993896 180)
			(unlocked yes)
			(layer "F.Fab")
			(hide yes)
			(effects
				(font
					(size 1.016 1.016)
					(thickness 0.1524)
				)
			)
		)
		(property "Device Type" "R402H16"
			(at 0.064008 -5.517896 180)
			(unlocked yes)
			(layer "F.Fab")
			(hide yes)
			(effects
				(font
					(size 1.016 1.016)
					(thickness 0.1524)
				)
			)
		)
		(duplicate_pad_numbers_are_jumpers no)
		(fp_line
			(start 0.508 -0.9398)
			(end -0.508 -0.9398)
			(stroke
				(width 0.1524)
				(type default)
			)
			(layer "F.SilkS")
		)
		(fp_line
			(start -0.508 -0.9398)
			(end -0.508 0.9398)
			(stroke
				(width 0.1524)
				(type default)
			)
			(layer "F.SilkS")
		)
		(fp_rect
			(start -0.508 0.9398)
			(end 0.508 -0.9398)
			(stroke
				(width 0)
				(type default)
			)
			(fill no)
			(layer "F.CrtYd")
		)
		(fp_rect
			(start -0.508 0.9398)
			(end 0.508 -0.9398)
			(stroke
				(width 0)
				(type default)
			)
			(fill no)
			(layer "F.Fab")
		)
		(pad "1" smd custom
			(at 0 -0.4445 180)
			(size 0.1397 0.1397)
			(layers "F.Cu" "F.Mask" "F.Paste")
			(net "P5V_STBY")
			(options
				(clearance outline)
				(anchor circle)
			)
			(primitives
				(gr_poly
					(pts
						(arc
							(start -0.1778 -0.2794)
							(mid -0.249642 -0.249642)
							(end -0.2794 -0.1778)
						)
						(arc
							(start -0.2794 0.1778)
							(mid -0.249642 0.249642)
							(end -0.1778 0.2794)
						)
						(arc
							(start 0.1778 0.2794)
							(mid 0.249642 0.249642)
							(end 0.2794 0.1778)
						)
						(arc
							(start 0.2794 -0.1778)
							(mid 0.249642 -0.249642)
							(end 0.1778 -0.2794)
						)
					)
					(width 0)
					(fill yes)
				)
			)
		)
		(pad "2" smd custom
			(at 0 0.4445 180)
			(size 0.1397 0.1397)
			(layers "F.Cu" "F.Mask" "F.Paste")
			(net "P1V15_STBY_PG_G")
			(options
				(clearance outline)
				(anchor circle)
			)
			(primitives
				(gr_poly
					(pts
						(arc
							(start -0.1778 -0.2794)
							(mid -0.249642 -0.249642)
							(end -0.2794 -0.1778)
						)
						(arc
							(start -0.2794 0.1778)
							(mid -0.249642 0.249642)
							(end -0.1778 0.2794)
						)
						(arc
							(start 0.1778 0.2794)
							(mid 0.249642 0.249642)
							(end 0.2794 0.1778)
						)
						(arc
							(start 0.2794 -0.1778)
							(mid 0.249642 -0.249642)
							(end 0.1778 -0.2794)
						)
					)
					(width 0)
					(fill yes)
				)
			)
		)
	)
	(footprint ""
		(layer "F.Cu")
		(at 88.138 -138.4554 90)
		(property "Reference" "R136"
			(at 0 0 90)
			(layer "F.SilkS")
			(hide yes)
			(effects
				(font
					(size 1.27 1.27)
				)
			)
		)
		(property "Value" "8K2R2J-3-GP"
			(at 0.064008 -3.993896 90)
			(unlocked yes)
			(layer "F.Fab")
			(hide yes)
			(effects
				(font
					(size 1.016 1.016)
					(thickness 0.1524)
				)
			)
		)
		(property "Device Type" "R402H16"
			(at 0.064008 -5.517896 90)
			(unlocked yes)
			(layer "F.Fab")
			(hide yes)
			(effects
				(font
					(size 1.016 1.016)
					(thickness 0.1524)
				)
			)
		)
		(duplicate_pad_numbers_are_jumpers no)
		(fp_line
			(start 0.508 -0.9398)
			(end -0.508 -0.9398)
			(stroke
				(width 0.1524)
				(type default)
			)
			(layer "F.SilkS")
		)
		(fp_line
			(start -0.508 -0.9398)
			(end -0.508 0.9398)
			(stroke
				(width 0.1524)
				(type default)
			)
			(layer "F.SilkS")
		)
		(fp_rect
			(start -0.508 0.9398)
			(end 0.508 -0.9398)
			(stroke
				(width 0)
				(type default)
			)
			(fill no)
			(layer "F.CrtYd")
		)
		(fp_rect
			(start -0.508 0.9398)
			(end 0.508 -0.9398)
			(stroke
				(width 0)
				(type default)
			)
			(fill no)
			(layer "F.Fab")
		)
		(pad "1" smd custom
			(at 0 -0.4445 90)
			(size 0.1397 0.1397)
			(layers "F.Cu" "F.Mask" "F.Paste")
			(net "EEPROM_A0")
			(options
				(clearance outline)
				(anchor circle)
			)
			(primitives
				(gr_poly
					(pts
						(arc
							(start -0.1778 -0.2794)
							(mid -0.249642 -0.249642)
							(end -0.2794 -0.1778)
						)
						(arc
							(start -0.2794 0.1778)
							(mid -0.249642 0.249642)
							(end -0.1778 0.2794)
						)
						(arc
							(start 0.1778 0.2794)
							(mid 0.249642 0.249642)
							(end 0.2794 0.1778)
						)
						(arc
							(start 0.2794 -0.1778)
							(mid 0.249642 -0.249642)
							(end 0.1778 -0.2794)
						)
					)
					(width 0)
					(fill yes)
				)
			)
		)
		(pad "2" smd custom
			(at 0 0.4445 90)
			(size 0.1397 0.1397)
			(layers "F.Cu" "F.Mask" "F.Paste")
			(net "GND")
			(options
				(clearance outline)
				(anchor circle)
			)
			(primitives
				(gr_poly
					(pts
						(arc
							(start -0.1778 -0.2794)
							(mid -0.249642 -0.249642)
							(end -0.2794 -0.1778)
						)
						(arc
							(start -0.2794 0.1778)
							(mid -0.249642 0.249642)
							(end -0.1778 0.2794)
						)
						(arc
							(start 0.1778 0.2794)
							(mid 0.249642 0.249642)
							(end 0.2794 0.1778)
						)
						(arc
							(start 0.2794 -0.1778)
							(mid 0.249642 -0.249642)
							(end 0.1778 -0.2794)
						)
					)
					(width 0)
					(fill yes)
				)
			)
		)
	)
	(footprint ""
		(layer "F.Cu")
		(at 180.213 -156.083 90)
		(property "Reference" "R468"
			(at 0 0 90)
			(layer "F.SilkS")
			(hide yes)
			(effects
				(font
					(size 1.27 1.27)
				)
			)
		)
		(property "Value" "3K3R2J-3-GP"
			(at 0.064008 -3.993896 90)
			(unlocked yes)
			(layer "F.Fab")
			(hide yes)
			(effects
				(font
					(size 1.016 1.016)
					(thickness 0.1524)
				)
			)
		)
		(property "Device Type" "R402H16"
			(at 0.064008 -5.517896 90)
			(unlocked yes)
			(layer "F.Fab")
			(hide yes)
			(effects
				(font
					(size 1.016 1.016)
					(thickness 0.1524)
				)
			)
		)
		(duplicate_pad_numbers_are_jumpers no)
		(fp_line
			(start 0.508 -0.9398)
			(end -0.508 -0.9398)
			(stroke
				(width 0.1524)
				(type default)
			)
			(layer "F.SilkS")
		)
		(fp_line
			(start -0.508 -0.9398)
			(end -0.508 0.9398)
			(stroke
				(width 0.1524)
				(type default)
			)
			(layer "F.SilkS")
		)
		(fp_rect
			(start -0.508 0.9398)
			(end 0.508 -0.9398)
			(stroke
				(width 0)
				(type default)
			)
			(fill no)
			(layer "F.CrtYd")
		)
		(fp_rect
			(start -0.508 0.9398)
			(end 0.508 -0.9398)
			(stroke
				(width 0)
				(type default)
			)
			(fill no)
			(layer "F.Fab")
		)
		(pad "1" smd custom
			(at 0 -0.4445 90)
			(size 0.1397 0.1397)
			(layers "F.Cu" "F.Mask" "F.Paste")
			(net "P5V_LL")
			(options
				(clearance outline)
				(anchor circle)
			)
			(primitives
				(gr_poly
					(pts
						(arc
							(start -0.1778 -0.2794)
							(mid -0.249642 -0.249642)
							(end -0.2794 -0.1778)
						)
						(arc
							(start -0.2794 0.1778)
							(mid -0.249642 0.249642)
							(end -0.1778 0.2794)
						)
						(arc
							(start 0.1778 0.2794)
							(mid 0.249642 0.249642)
							(end 0.2794 0.1778)
						)
						(arc
							(start 0.2794 -0.1778)
							(mid 0.249642 -0.249642)
							(end 0.1778 -0.2794)
						)
					)
					(width 0)
					(fill yes)
				)
			)
		)
		(pad "2" smd custom
			(at 0 0.4445 90)
			(size 0.1397 0.1397)
			(layers "F.Cu" "F.Mask" "F.Paste")
			(net "P5V_LL_R")
			(options
				(clearance outline)
				(anchor circle)
			)
			(primitives
				(gr_poly
					(pts
						(arc
							(start -0.1778 -0.2794)
							(mid -0.249642 -0.249642)
							(end -0.2794 -0.1778)
						)
						(arc
							(start -0.2794 0.1778)
							(mid -0.249642 0.249642)
							(end -0.1778 0.2794)
						)
						(arc
							(start 0.1778 0.2794)
							(mid 0.249642 0.249642)
							(end 0.2794 0.1778)
						)
						(arc
							(start 0.2794 -0.1778)
							(mid 0.249642 -0.249642)
							(end 0.1778 -0.2794)
						)
					)
					(width 0)
					(fill yes)
				)
			)
		)
	)
	(footprint ""
		(layer "F.Cu")
		(at 137.2362 -13.1064 180)
		(property "Reference" "R444"
			(at 0 0 180)
			(layer "F.SilkS")
			(hide yes)
			(effects
				(font
					(size 1.27 1.27)
				)
			)
		)
		(property "Value" "D002RL3115F-L-GP"
			(at 3.2258 1.2954 180)
			(unlocked yes)
			(layer "F.Fab")
			(hide yes)
			(effects
				(font
					(size 1.016 1.016)
					(thickness 0.1524)
				)
			)
		)
		(property "Device Type" "RL3115-4PH45"
			(at 3.2258 -0.2286 180)
			(unlocked yes)
			(layer "F.Fab")
			(hide yes)
			(effects
				(font
					(size 1.016 1.016)
					(thickness 0.1524)
				)
			)
		)
		(duplicate_pad_numbers_are_jumpers no)
		(fp_line
			(start 1.9685 1.651)
			(end -1.9685 1.651)
			(stroke
				(width 0.1524)
				(type default)
			)
			(layer "F.SilkS")
		)
		(fp_line
			(start 1.9685 -1.651)
			(end 1.9685 1.651)
			(stroke
				(width 0.1524)
				(type default)
			)
			(layer "F.SilkS")
		)
		(fp_line
			(start -0.5334 -1.7653)
			(end -2.0574 -1.7653)
			(stroke
				(width 0.3302)
				(type default)
			)
			(layer "F.SilkS")
		)
		(fp_line
			(start -1.9685 1.651)
			(end -1.9685 -1.651)
			(stroke
				(width 0.1524)
				(type default)
			)
			(layer "F.SilkS")
		)
		(fp_line
			(start -1.9685 -1.651)
			(end 1.9685 -1.651)
			(stroke
				(width 0.1524)
				(type default)
			)
			(layer "F.SilkS")
		)
		(fp_line
			(start -2.0574 -1.7653)
			(end -2.0574 -0.4064)
			(stroke
				(width 0.3302)
				(type default)
			)
			(layer "F.SilkS")
		)
		(fp_poly
			(pts
				(xy -0.561594 -1.726946) (xy -0.053594 -2.234946) (xy -1.069594 -2.234946)
			)
			(stroke
				(width 0)
				(type default)
			)
			(fill yes)
			(layer "F.SilkS")
		)
		(fp_rect
			(start -1.524 0.7493)
			(end 1.524 -0.7493)
			(stroke
				(width 0)
				(type default)
			)
			(fill no)
			(layer "F.CrtYd")
		)
		(fp_poly
			(pts
				(xy -2.2225 1.905) (xy -2.2225 -1.905) (xy 2.2225 -1.905) (xy 2.2225 -0.7493) (xy -1.524 -0.7493)
				(xy -1.524 0.7493) (xy 1.524 0.7493) (xy 1.524 -0.7366) (xy 2.2225 -0.7366) (xy 2.2225 1.905)
			)
			(stroke
				(width 0)
				(type default)
			)
			(fill no)
			(layer "F.CrtYd")
		)
		(fp_rect
			(start -2.2225 1.905)
			(end 2.2225 -1.905)
			(stroke
				(width 0)
				(type default)
			)
			(fill no)
			(layer "F.Fab")
		)
		(pad "1" smd rect
			(at -0.5715 -0.813562 180)
			(size 2.286 1.143)
			(layers "F.Cu" "F.Mask" "F.Paste")
			(net "MB0_P12V_MAIN_R")
		)
		(pad "2" smd rect
			(at -0.5715 0.813562 180)
			(size 2.286 1.143)
			(layers "F.Cu" "F.Mask" "F.Paste")
			(net "P12V_IOM")
		)
		(pad "3" smd rect
			(at 1.334008 -0.813562 180)
			(size 0.762 1.143)
			(layers "F.Cu" "F.Mask" "F.Paste")
			(net "MB0_CM_SENSE_R1_N")
		)
		(pad "4" smd rect
			(at 1.334008 0.813562 180)
			(size 0.762 1.143)
			(layers "F.Cu" "F.Mask" "F.Paste")
			(net "MB0_CM_SENSE_R1_P")
		)
		(zone
			(layer "F.Cu")
			(hatch none 0.5)
			(connect_pads
				(clearance 0)
			)
			(min_thickness 0.25)
			(keepout
				(tracks allowed)
				(vias not_allowed)
				(pads allowed)
				(copperpour not_allowed)
				(footprints allowed)
			)
			(placement
				(enabled no)
				(sheetname "")
			)
			(fill
				(thermal_gap 0.5)
				(thermal_bridge_width 0.5)
				(island_removal_mode 0)
			)
			(polygon
				(pts
					(xy 136.6647 -13.8557) (xy 136.283192 -13.8557) (xy 136.283192 -13.348462) (xy 136.6647 -13.348462)
				)
			)
		)
		(zone
			(layer "F.Cu")
			(hatch none 0.5)
			(connect_pads
				(clearance 0)
			)
			(min_thickness 0.25)
			(keepout
				(tracks not_allowed)
				(vias allowed)
				(pads allowed)
				(copperpour not_allowed)
				(footprints allowed)
			)
			(placement
				(enabled no)
				(sheetname "")
			)
			(fill
				(thermal_gap 0.5)
				(thermal_bridge_width 0.5)
				(island_removal_mode 0)
			)
			(polygon
				(pts
					(xy 136.6647 -13.8557) (xy 136.283192 -13.8557) (xy 136.283192 -13.348462) (xy 136.6647 -13.348462)
				)
			)
		)
		(zone
			(layer "F.Cu")
			(hatch none 0.5)
			(connect_pads
				(clearance 0)
			)
			(min_thickness 0.25)
			(keepout
				(tracks allowed)
				(vias not_allowed)
				(pads allowed)
				(copperpour not_allowed)
				(footprints allowed)
			)
			(placement
				(enabled no)
				(sheetname "")
			)
			(fill
				(thermal_gap 0.5)
				(thermal_bridge_width 0.5)
				(island_removal_mode 0)
			)
			(polygon
				(pts
					(xy 136.6647 -12.864338) (xy 136.283192 -12.864338) (xy 136.283192 -12.3571) (xy 136.6647 -12.3571)
				)
			)
		)
		(zone
			(layer "F.Cu")
			(hatch none 0.5)
			(connect_pads
				(clearance 0)
			)
			(min_thickness 0.25)
			(keepout
				(tracks not_allowed)
				(vias allowed)
				(pads allowed)
				(copperpour not_allowed)
				(footprints allowed)
			)
			(placement
				(enabled no)
				(sheetname "")
			)
			(fill
				(thermal_gap 0.5)
				(thermal_bridge_width 0.5)
				(island_removal_mode 0)
			)
			(polygon
				(pts
					(xy 136.6647 -12.864338) (xy 136.283192 -12.864338) (xy 136.283192 -12.3571) (xy 136.6647 -12.3571)
				)
			)
		)
	)
	(footprint ""
		(layer "F.Cu")
		(at 112.959388 -13.13561 180)
		(property "Reference" "R457"
			(at 0 0 180)
			(layer "F.SilkS")
			(hide yes)
			(effects
				(font
					(size 1.27 1.27)
				)
			)
		)
		(property "Value" "100KR2J-4-GP"
			(at 0.064008 -3.993896 180)
			(unlocked yes)
			(layer "F.Fab")
			(hide yes)
			(effects
				(font
					(size 1.016 1.016)
					(thickness 0.1524)
				)
			)
		)
		(property "Device Type" "R402H15"
			(at 0.064008 -5.517896 180)
			(unlocked yes)
			(layer "F.Fab")
			(hide yes)
			(effects
				(font
					(size 1.016 1.016)
					(thickness 0.1524)
				)
			)
		)
		(duplicate_pad_numbers_are_jumpers no)
		(fp_line
			(start 0.508 -0.9398)
			(end -0.508 -0.9398)
			(stroke
				(width 0.1524)
				(type default)
			)
			(layer "F.SilkS")
		)
		(fp_line
			(start -0.508 -0.9398)
			(end -0.508 0.9398)
			(stroke
				(width 0.1524)
				(type default)
			)
			(layer "F.SilkS")
		)
		(fp_rect
			(start -0.508 0.9398)
			(end 0.508 -0.9398)
			(stroke
				(width 0)
				(type default)
			)
			(fill no)
			(layer "F.CrtYd")
		)
		(fp_rect
			(start -0.508 0.9398)
			(end 0.508 -0.9398)
			(stroke
				(width 0)
				(type default)
			)
			(fill no)
			(layer "F.Fab")
		)
		(pad "1" smd custom
			(at 0 -0.4445 180)
			(size 0.1397 0.1397)
			(layers "F.Cu" "F.Mask" "F.Paste")
			(net "MB0_VCAP_R")
			(options
				(clearance outline)
				(anchor circle)
			)
			(primitives
				(gr_poly
					(pts
						(arc
							(start -0.1778 -0.2794)
							(mid -0.249642 -0.249642)
							(end -0.2794 -0.1778)
						)
						(arc
							(start -0.2794 0.1778)
							(mid -0.249642 0.249642)
							(end -0.1778 0.2794)
						)
						(arc
							(start 0.1778 0.2794)
							(mid 0.249642 0.249642)
							(end 0.2794 0.1778)
						)
						(arc
							(start 0.2794 -0.1778)
							(mid 0.249642 -0.249642)
							(end 0.1778 -0.2794)
						)
					)
					(width 0)
					(fill yes)
				)
			)
		)
		(pad "2" smd custom
			(at 0 0.4445 180)
			(size 0.1397 0.1397)
			(layers "F.Cu" "F.Mask" "F.Paste")
			(net "MB0_PSET_R")
			(options
				(clearance outline)
				(anchor circle)
			)
			(primitives
				(gr_poly
					(pts
						(arc
							(start -0.1778 -0.2794)
							(mid -0.249642 -0.249642)
							(end -0.2794 -0.1778)
						)
						(arc
							(start -0.2794 0.1778)
							(mid -0.249642 0.249642)
							(end -0.1778 0.2794)
						)
						(arc
							(start 0.1778 0.2794)
							(mid 0.249642 0.249642)
							(end 0.2794 0.1778)
						)
						(arc
							(start 0.2794 -0.1778)
							(mid 0.249642 -0.249642)
							(end 0.1778 -0.2794)
						)
					)
					(width 0)
					(fill yes)
				)
			)
		)
	)
	(footprint ""
		(layer "F.Cu")
		(at 28.194 -151.638 -90)
		(property "Reference" "R768"
			(at 0 0 270)
			(layer "F.SilkS")
			(hide yes)
			(effects
				(font
					(size 1.27 1.27)
				)
			)
		)
		(property "Value" "0R2J-2-GP"
			(at 0.064008 -3.993896 270)
			(unlocked yes)
			(layer "F.Fab")
			(hide yes)
			(effects
				(font
					(size 1.016 1.016)
					(thickness 0.1524)
				)
			)
		)
		(property "Device Type" "R402H16"
			(at 0.064008 -5.517896 270)
			(unlocked yes)
			(layer "F.Fab")
			(hide yes)
			(effects
				(font
					(size 1.016 1.016)
					(thickness 0.1524)
				)
			)
		)
		(duplicate_pad_numbers_are_jumpers no)
		(fp_line
			(start -0.508 -0.9398)
			(end -0.508 0.9398)
			(stroke
				(width 0.1524)
				(type default)
			)
			(layer "F.SilkS")
		)
		(fp_line
			(start 0.508 -0.9398)
			(end -0.508 -0.9398)
			(stroke
				(width 0.1524)
				(type default)
			)
			(layer "F.SilkS")
		)
		(fp_rect
			(start -0.508 0.9398)
			(end 0.508 -0.9398)
			(stroke
				(width 0)
				(type default)
			)
			(fill no)
			(layer "F.CrtYd")
		)
		(fp_rect
			(start -0.508 0.9398)
			(end 0.508 -0.9398)
			(stroke
				(width 0)
				(type default)
			)
			(fill no)
			(layer "F.Fab")
		)
		(pad "1" smd custom
			(at 0 -0.4445 270)
			(size 0.1397 0.1397)
			(layers "F.Cu" "F.Mask" "F.Paste")
			(net "DEBUG_GPIO_BMC_R_1")
			(options
				(clearance outline)
				(anchor circle)
			)
			(primitives
				(gr_poly
					(pts
						(arc
							(start -0.1778 -0.2794)
							(mid -0.249642 -0.249642)
							(end -0.2794 -0.1778)
						)
						(arc
							(start -0.2794 0.1778)
							(mid -0.249642 0.249642)
							(end -0.1778 0.2794)
						)
						(arc
							(start 0.1778 0.2794)
							(mid 0.249642 0.249642)
							(end 0.2794 0.1778)
						)
						(arc
							(start 0.2794 -0.1778)
							(mid 0.249642 -0.249642)
							(end 0.1778 -0.2794)
						)
					)
					(width 0)
					(fill yes)
				)
			)
		)
		(pad "2" smd custom
			(at 0 0.4445 270)
			(size 0.1397 0.1397)
			(layers "F.Cu" "F.Mask" "F.Paste")
			(net "DEBUG_GPIO_BMC_1")
			(options
				(clearance outline)
				(anchor circle)
			)
			(primitives
				(gr_poly
					(pts
						(arc
							(start -0.1778 -0.2794)
							(mid -0.249642 -0.249642)
							(end -0.2794 -0.1778)
						)
						(arc
							(start -0.2794 0.1778)
							(mid -0.249642 0.249642)
							(end -0.1778 0.2794)
						)
						(arc
							(start 0.1778 0.2794)
							(mid 0.249642 0.249642)
							(end 0.2794 0.1778)
						)
						(arc
							(start 0.2794 -0.1778)
							(mid 0.249642 -0.249642)
							(end 0.1778 -0.2794)
						)
					)
					(width 0)
					(fill yes)
				)
			)
		)
	)
)
